(kicad_pcb
	(version 20260206)
	(generator "pcbnew")
	(generator_version "10.0")
	(general
		(thickness 1.6)
		(legacy_teardrops no)
	)
	(paper "A4")
	(title_block
		(title "timecard-production-celestica-r4006 — R4006-B0001-02_R01.brd")
		(comment 1 "Time Appliance Project (Time Card) / footprints 489-494 of 1113")
	)
	(layers
		(0 "F.Cu" signal "TOP")
		(4 "In1.Cu" signal "L02_GND1")
		(6 "In2.Cu" signal "L03_SIG1")
		(8 "In3.Cu" signal "L04_GND2")
		(10 "In4.Cu" signal "L05_VCC1")
		(12 "In5.Cu" signal "L06_VCC2")
		(14 "In6.Cu" signal "L07_GND3")
		(16 "In7.Cu" signal "L08_SIG2")
		(18 "In8.Cu" signal "L09_GND4")
		(2 "B.Cu" signal "BOTTOM")
		(9 "F.Adhes" user "F.Adhesive")
		(11 "B.Adhes" user "B.Adhesive")
		(13 "F.Paste" user "Package Geometry/Pastemask Top")
		(15 "B.Paste" user "Package Geometry/Pastemask Bottom")
		(5 "F.SilkS" user "Ref Des/Silkscreen Top")
		(7 "B.SilkS" user "Ref Des/Silkscreen Bottom")
		(1 "F.Mask" user "Board Geometry/Soldermask Top")
		(3 "B.Mask" user "Board Geometry/Soldermask Bottom")
		(17 "Dwgs.User" user "User.Drawings")
		(19 "Cmts.User" user "User.Comments")
		(21 "Eco1.User" user "User.Eco1")
		(23 "Eco2.User" user "User.Eco2")
		(25 "Edge.Cuts" user "Board Geometry/Outline")
		(27 "Margin" user)
		(31 "F.CrtYd" user "Package Geometry/Place Bound Top")
		(29 "B.CrtYd" user "Package Geometry/Place Bound Bottom")
		(35 "F.Fab" user "Ref Des/Assembly Top")
		(33 "B.Fab" user "Ref Des/Assembly Bottom")
	)
	(footprint ""
		(layer "F.Cu")
		(at 97.282 -59.055 90)
		(property "Reference" "TP180"
			(at -2.9718 0.41275 90)
			(unlocked yes)
			(layer "F.SilkS")
			(effects
				(font
					(size 0.635 0.4064)
					(thickness 0.1524)
				)
				(justify left)
			)
		)
		(property "Value" ""
			(at 0 0 90)
			(layer "F.Fab")
			(effects
				(font
					(size 1.27 1.27)
				)
			)
		)
		(property "Device Type" "TP_PIONT-TP010CT020B030_PTH-TPA"
			(at -1.341882 0.996696 90)
			(unlocked yes)
			(layer "F.Fab")
			(hide yes)
			(effects
				(font
					(size 0.7874 0.5842)
					(thickness 0.1524)
				)
				(justify left)
			)
		)
		(duplicate_pad_numbers_are_jumpers no)
		(fp_poly
			(pts
				(arc
					(start 0 0.889)
					(mid 0 -0.889)
					(end 0 0.889)
				)
			)
			(stroke
				(width 0)
				(type default)
			)
			(fill no)
			(layer "B.CrtYd")
		)
		(fp_poly
			(pts
				(arc
					(start 0 0.889)
					(mid 0 -0.889)
					(end 0 0.889)
				)
			)
			(stroke
				(width 0)
				(type default)
			)
			(fill no)
			(layer "F.CrtYd")
		)
		(pad "1" thru_hole circle
			(at 0 0 90)
			(size 0.508 0.508)
			(drill 0.254)
			(layers "*.Cu" "*.Mask")
			(remove_unused_layers no)
			(net "IO_L20N_16")
			(clearance 0.1016)
			(padstack
				(mode front_inner_back)
				(layer "Inner"
					(shape circle)
					(size 0.508 0.508)
					(clearance 0.1016)
				)
				(layer "B.Cu"
					(shape circle)
					(size 0.762 0.762)
					(clearance -0.0254)
				)
			)
		)
	)
	(footprint ""
		(layer "F.Cu")
		(at 163.395406 -38.624002 90)
		(property "Reference" "J5"
			(at -0.524002 -14.258036 90)
			(unlocked yes)
			(layer "F.SilkS")
			(effects
				(font
					(size 0.7874 0.5842)
					(thickness 0.1524)
				)
			)
		)
		(property "Value" ""
			(at 0 0 90)
			(layer "F.Fab")
			(effects
				(font
					(size 1.27 1.27)
				)
			)
		)
		(property "Device Type" "CONN_HDR_2X6_F_S_SMT-G200-1313A"
			(at 0 5.682996 90)
			(unlocked yes)
			(layer "F.Fab")
			(hide yes)
			(effects
				(font
					(size 0.7874 0.5842)
					(thickness 0.000001)
				)
			)
		)
		(property "User Part Number" "PARTNUM*"
			(at 0 6.876796 90)
			(unlocked yes)
			(layer "Cmts.User")
			(hide yes)
			(effects
				(font
					(size 0.7874 0.5842)
					(thickness 0.000001)
				)
			)
		)
		(duplicate_pad_numbers_are_jumpers no)
		(fp_line
			(start 8.253984 -12.506706)
			(end 8.253984 4.574032)
			(stroke
				(width 0.1)
				(type default)
			)
			(layer "F.SilkS")
		)
		(fp_line
			(start -8.253984 -12.506706)
			(end 8.253984 -12.506706)
			(stroke
				(width 0.1)
				(type default)
			)
			(layer "F.SilkS")
		)
		(fp_line
			(start 8.253984 4.574032)
			(end -8.253984 4.574032)
			(stroke
				(width 0.1)
				(type default)
			)
			(layer "F.SilkS")
		)
		(fp_line
			(start -8.253984 4.574032)
			(end -8.253984 -12.506706)
			(stroke
				(width 0.1)
				(type default)
			)
			(layer "F.SilkS")
		)
		(fp_rect
			(start -8.507984 4.828032)
			(end 8.507984 -12.760706)
			(stroke
				(width 0)
				(type default)
			)
			(fill no)
			(layer "F.CrtYd")
		)
		(fp_line
			(start 7.999984 -4.320032)
			(end 7.999984 4.320032)
			(stroke
				(width 0.1)
				(type default)
			)
			(layer "F.Fab")
		)
		(fp_line
			(start -7.999984 -4.320032)
			(end 7.999984 -4.320032)
			(stroke
				(width 0.1)
				(type default)
			)
			(layer "F.Fab")
		)
		(fp_line
			(start 7.999984 4.320032)
			(end -7.999984 4.320032)
			(stroke
				(width 0.1)
				(type default)
			)
			(layer "F.Fab")
		)
		(fp_line
			(start -7.999984 4.320032)
			(end -7.999984 -4.320032)
			(stroke
				(width 0.1)
				(type default)
			)
			(layer "F.Fab")
		)
		(fp_text user "12"
			(at -6.786372 -14.170406 0)
			(unlocked yes)
			(layer "F.SilkS")
			(effects
				(font
					(size 0.7874 0.5842)
					(thickness 0.1524)
				)
			)
		)
		(fp_text user "2"
			(at 8.746998 -10.702036 90)
			(unlocked yes)
			(layer "F.SilkS")
			(effects
				(font
					(size 0.7874 0.5842)
					(thickness 0.1524)
				)
			)
		)
		(fp_text user "1"
			(at 8.492998 -7.527036 90)
			(unlocked yes)
			(layer "F.SilkS")
			(effects
				(font
					(size 0.7874 0.5842)
					(thickness 0.1524)
				)
			)
		)
		(fp_text user "11"
			(at -9.199372 -6.804406 0)
			(unlocked yes)
			(layer "F.SilkS")
			(effects
				(font
					(size 0.7874 0.5842)
					(thickness 0.1524)
				)
			)
		)
		(fp_text user "12"
			(at -8.310372 -12.392406 0)
			(unlocked yes)
			(layer "F.Fab")
			(effects
				(font
					(size 0.7874 0.5842)
					(thickness 0.1524)
				)
			)
		)
		(fp_text user "2"
			(at 8.326628 -11.884406 0)
			(unlocked yes)
			(layer "F.Fab")
			(effects
				(font
					(size 0.7874 0.5842)
					(thickness 0.1524)
				)
			)
		)
		(fp_text user "1"
			(at 8.580628 -6.296406 0)
			(unlocked yes)
			(layer "F.Fab")
			(effects
				(font
					(size 0.7874 0.5842)
					(thickness 0.1524)
				)
			)
		)
		(fp_text user "11"
			(at -8.437372 -5.915406 0)
			(unlocked yes)
			(layer "F.Fab")
			(effects
				(font
					(size 0.7874 0.5842)
					(thickness 0.1524)
				)
			)
		)
		(pad "1" smd rect
			(at 6.35 -7.274814 90)
			(size 1.4224 2.3368)
			(layers "F.Cu" "F.Mask" "F.Paste")
			(net "UNNAMED_16_CONNHDR2X6FSSMT_I161")
		)
		(pad "2" smd rect
			(at 6.35 -11.135106 90)
			(size 1.4224 2.2352)
			(layers "F.Cu" "F.Mask" "F.Paste")
			(net "UNNAMED_16_CONNHDR2X6FSSMT_I1_1")
		)
		(pad "3" smd rect
			(at 3.81 -7.274814 90)
			(size 1.4224 2.3368)
			(layers "F.Cu" "F.Mask" "F.Paste")
			(net "UNNAMED_16_CONNHDR2X6FSSMT_I1_2")
		)
		(pad "4" smd rect
			(at 3.81 -11.135106 90)
			(size 1.4224 2.2352)
			(layers "F.Cu" "F.Mask" "F.Paste")
			(net "UNNAMED_16_CONNHDR2X6FSSMT_I1_3")
		)
		(pad "5" smd rect
			(at 1.27 -7.274814 90)
			(size 1.4224 2.3368)
			(layers "F.Cu" "F.Mask" "F.Paste")
			(net "UNNAMED_16_CONNHDR2X6FSSMT_I1_6")
		)
		(pad "6" smd rect
			(at 1.27 -11.135106 90)
			(size 1.4224 2.2352)
			(layers "F.Cu" "F.Mask" "F.Paste")
			(net "UNNAMED_16_CONNHDR2X6FSSMT_I1_7")
		)
		(pad "7" smd rect
			(at -1.27 -7.274814 90)
			(size 1.4224 2.3368)
			(layers "F.Cu" "F.Mask" "F.Paste")
			(net "UNNAMED_16_CONNHDR2X6FSSMT_I1_4")
		)
		(pad "8" smd rect
			(at -1.27 -11.135106 90)
			(size 1.4224 2.2352)
			(layers "F.Cu" "F.Mask" "F.Paste")
			(net "UNNAMED_16_CONNHDR2X6FSSMT_I1_5")
		)
		(pad "9" smd rect
			(at -3.81 -7.274814 90)
			(size 1.4224 2.3368)
			(layers "F.Cu" "F.Mask" "F.Paste")
			(net "SG")
		)
		(pad "10" smd rect
			(at -3.81 -11.135106 90)
			(size 1.4224 2.2352)
			(layers "F.Cu" "F.Mask" "F.Paste")
			(net "SG")
		)
		(pad "11" smd rect
			(at -6.35 -7.274814 90)
			(size 1.4224 2.3368)
			(layers "F.Cu" "F.Mask" "F.Paste")
			(net "XP3R3V_FPGA")
		)
		(pad "12" smd rect
			(at -6.35 -11.135106 90)
			(size 1.4224 2.2352)
			(layers "F.Cu" "F.Mask" "F.Paste")
			(net "XP3R3V_FPGA")
		)
	)
	(footprint ""
		(layer "F.Cu")
		(at 11.798808 -57.2516 -90)
		(property "Reference" "R127"
			(at 0.3556 2.107438 90)
			(unlocked yes)
			(layer "F.SilkS")
			(effects
				(font
					(size 0.7874 0.5842)
					(thickness 0.1524)
				)
			)
		)
		(property "Value" "VAL*"
			(at 0.02032 2.13233 270)
			(unlocked yes)
			(layer "F.Fab")
			(hide yes)
			(effects
				(font
					(size 0.7874 0.5842)
					(thickness 0.1524)
				)
			)
		)
		(property "Tolerance" "TOL*"
			(at 0.044704 3.05435 270)
			(unlocked yes)
			(layer "Cmts.User")
			(hide yes)
			(effects
				(font
					(size 0.7874 0.5842)
					(thickness 0.1524)
				)
			)
		)
		(property "User Part Number" "PARTNUM*"
			(at 0.02032 4.024884 270)
			(unlocked yes)
			(layer "Cmts.User")
			(hide yes)
			(effects
				(font
					(size 0.7874 0.5842)
					(thickness 0.1524)
				)
			)
		)
		(property "Device Type" "RESISTOR-G155-149R9-01,49.9OHMA"
			(at 0.008382 1.210564 270)
			(unlocked yes)
			(layer "F.Fab")
			(hide yes)
			(effects
				(font
					(size 0.7874 0.5842)
					(thickness 0.1524)
				)
			)
		)
		(duplicate_pad_numbers_are_jumpers no)
		(fp_line
			(start -1.143 0.5588)
			(end 1.143 0.5588)
			(stroke
				(width 0.1)
				(type default)
			)
			(layer "F.SilkS")
		)
		(fp_line
			(start 1.143 0.5588)
			(end 1.143 -0.5588)
			(stroke
				(width 0.1)
				(type default)
			)
			(layer "F.SilkS")
		)
		(fp_line
			(start -1.143 -0.5588)
			(end -1.143 0.5588)
			(stroke
				(width 0.1)
				(type default)
			)
			(layer "F.SilkS")
		)
		(fp_line
			(start 1.143 -0.5588)
			(end -1.143 -0.5588)
			(stroke
				(width 0.1)
				(type default)
			)
			(layer "F.SilkS")
		)
		(fp_poly
			(pts
				(xy -1.143 0.5588) (xy 1.143 0.5588) (xy 1.143 -0.5588) (xy -1.143 -0.5588)
			)
			(stroke
				(width 0)
				(type default)
			)
			(fill no)
			(layer "F.CrtYd")
		)
		(fp_line
			(start -0.508 0.3048)
			(end 0.508 0.3048)
			(stroke
				(width 0.1)
				(type default)
			)
			(layer "F.Fab")
		)
		(fp_line
			(start 0.508 0.3048)
			(end 0.508 -0.3048)
			(stroke
				(width 0.1)
				(type default)
			)
			(layer "F.Fab")
		)
		(fp_line
			(start -0.508 -0.3048)
			(end -0.508 0.3048)
			(stroke
				(width 0.1)
				(type default)
			)
			(layer "F.Fab")
		)
		(fp_line
			(start 0.508 -0.3048)
			(end -0.508 -0.3048)
			(stroke
				(width 0.1)
				(type default)
			)
			(layer "F.Fab")
		)
		(pad "1" smd rect
			(at -0.5334 0 270)
			(size 0.7112 0.6096)
			(layers "F.Cu" "F.Mask" "F.Paste")
			(net "BF_SMA1_SIG_IO_CONN")
		)
		(pad "2" smd rect
			(at 0.5334 0 270)
			(size 0.7112 0.6096)
			(layers "F.Cu" "F.Mask" "F.Paste")
			(net "SMA1_SIG_IO_CONN")
		)
		(zone
			(layer "F.Cu")
			(hatch none 0.5)
			(connect_pads
				(clearance 0)
			)
			(min_thickness 0.25)
			(keepout
				(tracks allowed)
				(vias not_allowed)
				(pads allowed)
				(copperpour not_allowed)
				(footprints allowed)
			)
			(placement
				(enabled no)
				(sheetname "")
			)
			(fill
				(thermal_gap 0.5)
				(thermal_bridge_width 0.5)
				(island_removal_mode 0)
			)
			(polygon
				(pts
					(xy 11.494008 -57.3278) (xy 11.494008 -57.1754) (xy 12.103608 -57.1754) (xy 12.103608 -57.3278)
				)
			)
		)
		(zone
			(layer "F.Cu")
			(hatch none 0.5)
			(connect_pads
				(clearance 0)
			)
			(min_thickness 0.25)
			(keepout
				(tracks not_allowed)
				(vias allowed)
				(pads allowed)
				(copperpour not_allowed)
				(footprints allowed)
			)
			(placement
				(enabled no)
				(sheetname "")
			)
			(fill
				(thermal_gap 0.5)
				(thermal_bridge_width 0.5)
				(island_removal_mode 0)
			)
			(polygon
				(pts
					(xy 11.494008 -57.3278) (xy 11.494008 -57.1754) (xy 12.103608 -57.1754) (xy 12.103608 -57.3278)
				)
			)
		)
	)
	(footprint ""
		(layer "F.Cu")
		(at 16.4338 -63.9318)
		(property "Reference" "TP32"
			(at -0.52705 3.1242 90)
			(unlocked yes)
			(layer "F.SilkS")
			(effects
				(font
					(size 0.635 0.4064)
					(thickness 0.1524)
				)
				(justify left)
			)
		)
		(property "Value" ""
			(at 0 0 0)
			(layer "F.Fab")
			(effects
				(font
					(size 1.27 1.27)
				)
			)
		)
		(property "Device Type" "TP_PIONT-TP010CT020B030_PTH-TPA"
			(at -1.341882 0.996696 0)
			(unlocked yes)
			(layer "F.Fab")
			(hide yes)
			(effects
				(font
					(size 0.7874 0.5842)
					(thickness 0.000001)
				)
				(justify left)
			)
		)
		(duplicate_pad_numbers_are_jumpers no)
		(fp_poly
			(pts
				(arc
					(start 0.889 0)
					(mid -0.889 0)
					(end 0.889 0)
				)
			)
			(stroke
				(width 0)
				(type default)
			)
			(fill no)
			(layer "B.CrtYd")
		)
		(fp_poly
			(pts
				(arc
					(start 0.889 0)
					(mid -0.889 0)
					(end 0.889 0)
				)
			)
			(stroke
				(width 0)
				(type default)
			)
			(fill no)
			(layer "F.CrtYd")
		)
		(pad "1" thru_hole circle
			(at 0 0)
			(size 0.508 0.508)
			(drill 0.254)
			(layers "*.Cu" "*.Mask")
			(remove_unused_layers no)
			(net "SMA1_SIG_OUT_BF_EN_N")
			(clearance 0.1016)
			(padstack
				(mode front_inner_back)
				(layer "Inner"
					(shape circle)
					(size 0.508 0.508)
					(clearance 0.1016)
				)
				(layer "B.Cu"
					(shape circle)
					(size 0.762 0.762)
					(clearance -0.0254)
				)
			)
		)
	)
	(footprint ""
		(layer "F.Cu")
		(at 106.299 -29.718 90)
		(property "Reference" "TP196"
			(at -1.5748 -0.85725 90)
			(unlocked yes)
			(layer "F.SilkS")
			(effects
				(font
					(size 0.635 0.4064)
					(thickness 0.1524)
				)
				(justify left)
			)
		)
		(property "Value" ""
			(at 0 0 90)
			(layer "F.Fab")
			(effects
				(font
					(size 1.27 1.27)
				)
			)
		)
		(property "Device Type" "TP_PIONT-TP010CT020B030_PTH-TPA"
			(at -1.341882 0.996696 90)
			(unlocked yes)
			(layer "F.Fab")
			(hide yes)
			(effects
				(font
					(size 0.7874 0.5842)
					(thickness 0.1524)
				)
				(justify left)
			)
		)
		(duplicate_pad_numbers_are_jumpers no)
		(fp_poly
			(pts
				(arc
					(start 0 0.889)
					(mid 0 -0.889)
					(end 0 0.889)
				)
			)
			(stroke
				(width 0)
				(type default)
			)
			(fill no)
			(layer "B.CrtYd")
		)
		(fp_poly
			(pts
				(arc
					(start 0 0.889)
					(mid 0 -0.889)
					(end 0 0.889)
				)
			)
			(stroke
				(width 0)
				(type default)
			)
			(fill no)
			(layer "F.CrtYd")
		)
		(pad "1" thru_hole circle
			(at 0 0 90)
			(size 0.508 0.508)
			(drill 0.254)
			(layers "*.Cu" "*.Mask")
			(remove_unused_layers no)
			(net "IO_L23N_35")
			(clearance 0.1016)
			(padstack
				(mode front_inner_back)
				(layer "Inner"
					(shape circle)
					(size 0.508 0.508)
					(clearance 0.1016)
				)
				(layer "B.Cu"
					(shape circle)
					(size 0.762 0.762)
					(clearance -0.0254)
				)
			)
		)
	)
	(footprint ""
		(layer "F.Cu")
		(at 126.0094 -68.7578 90)
		(property "Reference" "C187"
			(at 4.10083 -0.0254 0)
			(unlocked yes)
			(layer "F.SilkS")
			(effects
				(font
					(size 0.7874 0.5842)
					(thickness 0.1524)
				)
			)
		)
		(property "Value" "VAL*"
			(at 0.0762 2.067306 90)
			(unlocked yes)
			(layer "F.Fab")
			(hide yes)
			(effects
				(font
					(size 0.7874 0.5842)
					(thickness 0.1524)
				)
			)
		)
		(property "Tolerance" "TOL*"
			(at 0.0762 3.032506 90)
			(unlocked yes)
			(layer "Cmts.User")
			(hide yes)
			(effects
				(font
					(size 0.7874 0.5842)
					(thickness 0.1524)
				)
			)
		)
		(property "User Part Number" "PARTNUM*"
			(at 0.1016 4.023106 90)
			(unlocked yes)
			(layer "Cmts.User")
			(hide yes)
			(effects
				(font
					(size 0.7874 0.5842)
					(thickness 0.1524)
				)
			)
		)
		(property "Device Type" "CAPACITOR-G105-0B104-EK,0.1UF,A"
			(at 0.0508 1.127506 90)
			(unlocked yes)
			(layer "F.Fab")
			(hide yes)
			(effects
				(font
					(size 0.7874 0.5842)
					(thickness 0.1524)
				)
			)
		)
		(duplicate_pad_numbers_are_jumpers no)
		(fp_line
			(start 1.143 -0.5588)
			(end -1.143 -0.5588)
			(stroke
				(width 0.1)
				(type default)
			)
			(layer "F.SilkS")
		)
		(fp_line
			(start -1.143 -0.5588)
			(end -1.143 0.5588)
			(stroke
				(width 0.1)
				(type default)
			)
			(layer "F.SilkS")
		)
		(fp_line
			(start 1.143 0.5588)
			(end 1.143 -0.5588)
			(stroke
				(width 0.1)
				(type default)
			)
			(layer "F.SilkS")
		)
		(fp_line
			(start -1.143 0.5588)
			(end 1.143 0.5588)
			(stroke
				(width 0.1)
				(type default)
			)
			(layer "F.SilkS")
		)
		(fp_rect
			(start 1.143 0.5588)
			(end -1.143 -0.5588)
			(stroke
				(width 0)
				(type default)
			)
			(fill no)
			(layer "F.CrtYd")
		)
		(fp_line
			(start 0.508 -0.3048)
			(end -0.508 -0.3048)
			(stroke
				(width 0.1)
				(type default)
			)
			(layer "F.Fab")
		)
		(fp_line
			(start -0.508 -0.3048)
			(end -0.508 0.3048)
			(stroke
				(width 0.1)
				(type default)
			)
			(layer "F.Fab")
		)
		(fp_line
			(start 0.508 0.3048)
			(end 0.508 -0.3048)
			(stroke
				(width 0.1)
				(type default)
			)
			(layer "F.Fab")
		)
		(fp_line
			(start -0.508 0.3048)
			(end 0.508 0.3048)
			(stroke
				(width 0.1)
				(type default)
			)
			(layer "F.Fab")
		)
		(pad "1" smd rect
			(at -0.5334 0 90)
			(size 0.7112 0.6096)
			(layers "F.Cu" "F.Mask" "F.Paste")
			(net "XP1R8V_EN_R")
		)
		(pad "2" smd rect
			(at 0.5334 0 90)
			(size 0.7112 0.6096)
			(layers "F.Cu" "F.Mask" "F.Paste")
			(net "SG")
		)
		(zone
			(layer "F.Cu")
			(hatch none 0.5)
			(connect_pads
				(clearance 0)
			)
			(min_thickness 0.25)
			(keepout
				(tracks allowed)
				(vias not_allowed)
				(pads allowed)
				(copperpour not_allowed)
				(footprints allowed)
			)
			(placement
				(enabled no)
				(sheetname "")
			)
			(fill
				(thermal_gap 0.5)
				(thermal_bridge_width 0.5)
				(island_removal_mode 0)
			)
			(polygon
				(pts
					(xy 126.3142 -68.834) (xy 125.7046 -68.834) (xy 125.7046 -68.6816) (xy 126.3142 -68.6816)
				)
			)
		)
	)
)
